(kicad_pcb
	(version 20260206)
	(generator "pcbnew")
	(generator_version "10.0")
	(general
		(thickness 1.6)
		(legacy_teardrops no)
	)
	(paper "A4")
	(title_block
		(title "04192023_DAF0TMB3IC0_F0TG_MB_C_brd_V02_OCP.brd")
		(comment 1 "Grand Teton / footprints 1307-1310 of 8354")
	)
	(layers
		(0 "F.Cu" signal "TOP")
		(4 "In1.Cu" signal "GND")
		(6 "In2.Cu" signal "IN1")
		(8 "In3.Cu" signal "GND1")
		(10 "In4.Cu" signal "IN2")
		(12 "In5.Cu" signal "GND2")
		(14 "In6.Cu" signal "IN3")
		(16 "In7.Cu" signal "GND3")
		(18 "In8.Cu" signal "VCC")
		(20 "In9.Cu" signal "VCC1")
		(22 "In10.Cu" signal "GND4")
		(24 "In11.Cu" signal "IN4")
		(26 "In12.Cu" signal "GND5")
		(28 "In13.Cu" signal "IN5")
		(30 "In14.Cu" signal "GND6")
		(32 "In15.Cu" signal "IN6")
		(34 "In16.Cu" signal "GND7")
		(2 "B.Cu" signal "BOTTOM")
		(9 "F.Adhes" user "F.Adhesive")
		(11 "B.Adhes" user "B.Adhesive")
		(13 "F.Paste" user "Package Geometry/Pastemask Top")
		(15 "B.Paste" user "Package Geometry/Pastemask Bottom")
		(5 "F.SilkS" user "Ref Des/Silkscreen Top")
		(7 "B.SilkS" user "Ref Des/Silkscreen Bottom")
		(1 "F.Mask" user "Board Geometry/Soldermask Top")
		(3 "B.Mask" user "Board Geometry/Soldermask Bottom")
		(17 "Dwgs.User" user "User.Drawings")
		(19 "Cmts.User" user "User.Comments")
		(21 "Eco1.User" user "User.Eco1")
		(23 "Eco2.User" user "User.Eco2")
		(25 "Edge.Cuts" user "Board Geometry/Outline")
		(27 "Margin" user)
		(31 "F.CrtYd" user "Package Geometry/Place Bound Top")
		(29 "B.CrtYd" user "Package Geometry/Place Bound Bottom")
		(35 "F.Fab" user "Ref Des/Assembly Top")
		(33 "B.Fab" user "Ref Des/Assembly Bottom")
	)
	(footprint ""
		(layer "F.Cu")
		(at 423.64406 -351.114868)
		(property "Reference" "PU22"
			(at -5.372862 3.17627 90)
			(unlocked yes)
			(layer "F.SilkS")
			(effects
				(font
					(size 0.7874 0.5842)
					(thickness 0.1524)
				)
				(justify left)
			)
		)
		(property "Value" ""
			(at 0 0 0)
			(layer "F.Fab")
			(effects
				(font
					(size 1.27 1.27)
				)
			)
		)
		(duplicate_pad_numbers_are_jumpers no)
		(fp_line
			(start -2.500122 -2.999994)
			(end -2.24409 -2.999994)
			(stroke
				(width 0.1524)
				(type default)
			)
			(layer "F.SilkS")
		)
		(fp_line
			(start -2.500122 -2.529078)
			(end -2.500122 -2.999994)
			(stroke
				(width 0.1524)
				(type default)
			)
			(layer "F.SilkS")
		)
		(fp_line
			(start -2.500122 0.6604)
			(end -2.500122 0.229108)
			(stroke
				(width 0.1524)
				(type default)
			)
			(layer "F.SilkS")
		)
		(fp_line
			(start -2.500122 2.999994)
			(end -2.500122 2.339594)
			(stroke
				(width 0.1524)
				(type default)
			)
			(layer "F.SilkS")
		)
		(fp_line
			(start -2.2987 2.999994)
			(end -2.500122 2.999994)
			(stroke
				(width 0.1524)
				(type default)
			)
			(layer "F.SilkS")
		)
		(fp_line
			(start 2.31394 -2.999994)
			(end 2.500122 -2.999994)
			(stroke
				(width 0.1524)
				(type default)
			)
			(layer "F.SilkS")
		)
		(fp_line
			(start 2.500122 -2.999994)
			(end 2.500122 -2.44348)
			(stroke
				(width 0.1524)
				(type default)
			)
			(layer "F.SilkS")
		)
		(fp_line
			(start 2.500122 2.339594)
			(end 2.500122 2.999994)
			(stroke
				(width 0.1524)
				(type default)
			)
			(layer "F.SilkS")
		)
		(fp_line
			(start 2.500122 2.999994)
			(end 2.2987 2.999994)
			(stroke
				(width 0.1524)
				(type default)
			)
			(layer "F.SilkS")
		)
		(fp_poly
			(pts
				(xy -2.712974 -2.443988) (xy -3.386328 -2.668524) (xy -2.93751 -3.117596)
			)
			(stroke
				(width 0)
				(type default)
			)
			(fill yes)
			(layer "F.SilkS")
		)
		(fp_line
			(start -2.500122 -2.999994)
			(end 2.500122 -2.999994)
			(stroke
				(width 0.1)
				(type default)
			)
			(layer "F.Fab")
		)
		(fp_line
			(start -2.500122 2.999994)
			(end -2.500122 -2.999994)
			(stroke
				(width 0.1)
				(type default)
			)
			(layer "F.Fab")
		)
		(fp_line
			(start 2.500122 -2.999994)
			(end 2.500122 2.999994)
			(stroke
				(width 0.1)
				(type default)
			)
			(layer "F.Fab")
		)
		(fp_line
			(start 2.500122 2.999994)
			(end -2.500122 2.999994)
			(stroke
				(width 0.1)
				(type default)
			)
			(layer "F.Fab")
		)
		(fp_poly
			(pts
				(xy -4.218432 -2.783078) (xy -4.218432 -1.767078) (xy -3.202432 -2.275078)
			)
			(stroke
				(width 0)
				(type default)
			)
			(fill yes)
			(layer "F.Fab")
		)
		(pad "1" smd rect
			(at -2.400046 -2.275078 90)
			(size 0.2286 0.6096)
			(layers "F.Cu" "F.Mask" "F.Paste")
			(net "PVDD11_S3_P0_VOS1")
		)
		(pad "2" smd rect
			(at -2.400046 -1.82499 90)
			(size 0.2286 0.6096)
			(layers "F.Cu" "F.Mask" "F.Paste")
			(net "GND")
		)
		(pad "3" smd rect
			(at -2.400046 -1.374902 90)
			(size 0.2286 0.6096)
			(layers "F.Cu" "F.Mask" "F.Paste")
			(net "PVDD11_S3_P0_VCC1")
		)
		(pad "4" smd rect
			(at -2.400046 -0.925068 90)
			(size 0.2286 0.6096)
			(layers "F.Cu" "F.Mask" "F.Paste")
			(net "PVDD11_S3_P0_PVCC")
		)
		(pad "5" smd rect
			(at -2.400046 -0.47498 90)
			(size 0.2286 0.6096)
			(layers "F.Cu" "F.Mask" "F.Paste")
			(net "GND")
		)
		(pad "6" smd rect
			(at -2.400046 -0.024892 90)
			(size 0.2286 0.6096)
			(layers "F.Cu" "F.Mask" "F.Paste")
			(net "NC_PVDD11_S3_P0_GL1_1")
		)
		(pad "7_9-20_24" smd circle
			(at 0 1.150112 90)
			(size 0 0)
			(layers "F.Cu" "F.Mask" "F.Paste")
			(net "GND")
		)
		(pad "10_19" smd rect
			(at 0 2.899918 90)
			(size 0.6096 4.318)
			(layers "F.Cu" "F.Mask" "F.Paste")
			(net "SW_PVDD11_S3_P0_SW1")
		)
		(pad "25_29" smd rect
			(at 1.549908 -1.279906 270)
			(size 2.0574 2.3114)
			(layers "F.Cu" "F.Mask" "F.Paste")
			(net "SW_P12V_AUX_PVDD11_S3_P0_FLT")
		)
		(pad "30" smd rect
			(at 2.05994 -2.899918)
			(size 0.2286 0.6096)
			(layers "F.Cu" "F.Mask" "F.Paste")
			(net "SW_P12V_AUX_PVDD11_S3_P0_FLT")
		)
		(pad "31" smd rect
			(at 1.610106 -2.899918)
			(size 0.2286 0.6096)
			(layers "F.Cu" "F.Mask" "F.Paste")
			(net "NC_PVDD11_S3_P0_DNC1")
		)
		(pad "32" smd rect
			(at 1.160018 -2.899918)
			(size 0.2286 0.6096)
			(layers "F.Cu" "F.Mask" "F.Paste")
			(net "SW_PVDD11_S3_P0_PH1")
		)
		(pad "33" smd rect
			(at 0.70993 -2.899918)
			(size 0.2286 0.6096)
			(layers "F.Cu" "F.Mask" "F.Paste")
			(net "SW_PVDD11_S3_P0_BOOT1")
		)
		(pad "34" smd rect
			(at 0.260096 -2.899918)
			(size 0.2286 0.6096)
			(layers "F.Cu" "F.Mask" "F.Paste")
			(net "PVDD11_S3_P0_PWM1")
		)
		(pad "35" smd rect
			(at -0.189992 -2.899918)
			(size 0.2286 0.6096)
			(layers "F.Cu" "F.Mask" "F.Paste")
			(net "PVDD11_S3_P0_VCC1")
		)
		(pad "36" smd rect
			(at -0.64008 -2.899918)
			(size 0.2286 0.6096)
			(layers "F.Cu" "F.Mask" "F.Paste")
			(net "PVDD11_S3_P0_TEMP0")
		)
		(pad "37" smd rect
			(at -1.089914 -2.899918)
			(size 0.2286 0.6096)
			(layers "F.Cu" "F.Mask" "F.Paste")
			(net "PVDD11_S3_P0_LSET1")
		)
		(pad "38" smd rect
			(at -1.540002 -2.899918)
			(size 0.2286 0.6096)
			(layers "F.Cu" "F.Mask" "F.Paste")
			(net "PVDD11_S3_P0_IMON1")
		)
		(pad "39" smd rect
			(at -1.99009 -2.899918)
			(size 0.2286 0.6096)
			(layers "F.Cu" "F.Mask" "F.Paste")
			(net "PVDD11_S3_P0_VCCS")
		)
		(pad "40" smd rect
			(at -0.87503 -1.27508)
			(size 1.7526 1.9558)
			(layers "F.Cu" "F.Mask" "F.Paste")
			(net "GND")
		)
		(pad "41" smd rect
			(at -1.525016 0.249936 270)
			(size 0.3048 0.4572)
			(layers "F.Cu" "F.Mask" "F.Paste")
			(net "NC_PVDD11_S3_P0_GL2_1")
		)
		(zone
			(layer "F.Cu")
			(hatch none 0.5)
			(connect_pads
				(clearance 0)
			)
			(min_thickness 0.25)
			(keepout
				(tracks not_allowed)
				(vias allowed)
				(pads allowed)
				(copperpour not_allowed)
				(footprints allowed)
			)
			(placement
				(enabled no)
				(sheetname "")
			)
			(fill
				(thermal_gap 0.5)
				(thermal_bridge_width 0.5)
				(island_removal_mode 0)
			)
			(polygon
				(pts
					(xy 421.143938 -348.54007) (xy 421.143938 -348.864174) (xy 426.144182 -348.864174) (xy 426.144182 -348.114874)
					(xy 425.85386 -348.114874) (xy 425.85386 -348.57055) (xy 421.43426 -348.57055) (xy 421.43426 -348.54007)
				)
			)
		)
		(zone
			(layer "F.Cu")
			(hatch none 0.5)
			(connect_pads
				(clearance 0)
			)
			(min_thickness 0.25)
			(keepout
				(tracks not_allowed)
				(vias allowed)
				(pads allowed)
				(copperpour not_allowed)
				(footprints allowed)
			)
			(placement
				(enabled no)
				(sheetname "")
			)
			(fill
				(thermal_gap 0.5)
				(thermal_bridge_width 0.5)
				(island_removal_mode 0)
			)
			(polygon
				(pts
					(xy 423.69613 -351.361248) (xy 423.69613 -353.418648) (xy 421.84193 -353.418648) (xy 421.84193 -353.177602)
					(xy 421.599614 -353.177602) (xy 421.599614 -353.659186) (xy 425.4246 -353.659186) (xy 425.4246 -353.474274)
					(xy 423.987468 -353.474274) (xy 423.987468 -351.315274) (xy 426.144182 -351.315274) (xy 426.144182 -351.065592)
					(xy 423.991786 -351.065592)
				)
			)
		)
	)
	(footprint ""
		(layer "F.Cu")
		(at 264.387076 -421.169084 180)
		(property "Reference" "C1115"
			(at 0 0 180)
			(layer "F.SilkS")
			(hide yes)
			(effects
				(font
					(size 1.27 1.27)
				)
			)
		)
		(property "Value" ""
			(at 0 0 180)
			(layer "F.Fab")
			(effects
				(font
					(size 1.27 1.27)
				)
			)
		)
		(duplicate_pad_numbers_are_jumpers no)
		(fp_line
			(start 1.524 0.762)
			(end -1.524 0.762)
			(stroke
				(width 0.1524)
				(type default)
			)
			(layer "F.SilkS")
		)
		(fp_line
			(start 1.524 -0.762)
			(end 1.524 0.762)
			(stroke
				(width 0.1524)
				(type default)
			)
			(layer "F.SilkS")
		)
		(fp_line
			(start -1.524 0.762)
			(end -1.524 -0.762)
			(stroke
				(width 0.1524)
				(type default)
			)
			(layer "F.SilkS")
		)
		(fp_line
			(start -1.524 -0.762)
			(end 1.524 -0.762)
			(stroke
				(width 0.1524)
				(type default)
			)
			(layer "F.SilkS")
		)
		(fp_line
			(start 1.1049 0.724916)
			(end 1.1049 -0.724916)
			(stroke
				(width 0.1)
				(type default)
			)
			(layer "F.Fab")
		)
		(fp_line
			(start 1.1049 -0.724916)
			(end -1.1049 -0.724916)
			(stroke
				(width 0.1)
				(type default)
			)
			(layer "F.Fab")
		)
		(fp_line
			(start -1.1049 0.724916)
			(end 1.1049 0.724916)
			(stroke
				(width 0.1)
				(type default)
			)
			(layer "F.Fab")
		)
		(fp_line
			(start -1.1049 -0.724916)
			(end -1.1049 0.724916)
			(stroke
				(width 0.1)
				(type default)
			)
			(layer "F.Fab")
		)
		(pad "1" smd rect
			(at -0.889 0)
			(size 1.016 1.27)
			(layers "F.Cu" "F.Mask" "F.Paste")
			(net "PDB_PRSNT_R_N")
		)
		(pad "2" smd rect
			(at 0.889 0)
			(size 1.016 1.27)
			(layers "F.Cu" "F.Mask" "F.Paste")
			(net "GND")
		)
	)
	(footprint ""
		(layer "F.Cu")
		(at 178.187604 -151.764238 -90)
		(property "Reference" "U27"
			(at 0.229108 -2.722118 0)
			(unlocked yes)
			(layer "F.SilkS")
			(effects
				(font
					(size 0.7874 0.5842)
					(thickness 0.1524)
				)
				(justify left)
			)
		)
		(property "Value" ""
			(at 0 0 270)
			(layer "F.Fab")
			(effects
				(font
					(size 1.27 1.27)
				)
			)
		)
		(duplicate_pad_numbers_are_jumpers no)
		(fp_line
			(start -1.463548 1.549908)
			(end -1.463548 -1.549908)
			(stroke
				(width 0.1524)
				(type default)
			)
			(layer "F.SilkS")
		)
		(fp_line
			(start 1.463548 1.549908)
			(end -1.463548 1.549908)
			(stroke
				(width 0.1524)
				(type default)
			)
			(layer "F.SilkS")
		)
		(fp_line
			(start 0 -0.762)
			(end 0.762 -1.549908)
			(stroke
				(width 0.1524)
				(type default)
			)
			(layer "F.SilkS")
		)
		(fp_line
			(start -1.463548 -1.549908)
			(end -0.787908 -1.549908)
			(stroke
				(width 0.1524)
				(type default)
			)
			(layer "F.SilkS")
		)
		(fp_line
			(start -0.787908 -1.549908)
			(end 0 -0.762)
			(stroke
				(width 0.1524)
				(type default)
			)
			(layer "F.SilkS")
		)
		(fp_line
			(start 0.762 -1.549908)
			(end 1.463548 -1.549908)
			(stroke
				(width 0.1524)
				(type default)
			)
			(layer "F.SilkS")
		)
		(fp_line
			(start 1.463548 -1.549908)
			(end 1.463548 1.549908)
			(stroke
				(width 0.1524)
				(type default)
			)
			(layer "F.SilkS")
		)
		(fp_poly
			(pts
				(xy -3.4798 -0.740156) (xy -3.4798 -1.359916) (xy -2.86004 -1.050036)
			)
			(stroke
				(width 0)
				(type default)
			)
			(fill yes)
			(layer "F.SilkS")
		)
		(fp_line
			(start -1.549908 1.549908)
			(end -1.549908 -1.549908)
			(stroke
				(width 0.1)
				(type default)
			)
			(layer "F.Fab")
		)
		(fp_line
			(start 1.549908 1.549908)
			(end -1.549908 1.549908)
			(stroke
				(width 0.1)
				(type default)
			)
			(layer "F.Fab")
		)
		(fp_line
			(start -1.549908 -1.549908)
			(end 1.549908 -1.549908)
			(stroke
				(width 0.1)
				(type default)
			)
			(layer "F.Fab")
		)
		(fp_line
			(start 1.549908 -1.549908)
			(end 1.549908 1.549908)
			(stroke
				(width 0.1)
				(type default)
			)
			(layer "F.Fab")
		)
		(fp_poly
			(pts
				(xy -3.4798 -1.359916) (xy -2.86004 -1.050036) (xy -3.4798 -0.740156)
			)
			(stroke
				(width 0)
				(type default)
			)
			(fill yes)
			(layer "F.Fab")
		)
		(pad "1" smd rect
			(at -2.175002 -1.050036)
			(size 0.6096 1.1684)
			(layers "F.Cu" "F.Mask" "F.Paste")
			(net "PVDD18_S5_P0")
		)
		(pad "2" smd rect
			(at -2.175002 -0.32512)
			(size 0.4318 1.1684)
			(layers "F.Cu" "F.Mask" "F.Paste")
			(net "SMB_CPU0_4_SCL")
		)
		(pad "3" smd rect
			(at -2.175002 0.32512)
			(size 0.4318 1.1684)
			(layers "F.Cu" "F.Mask" "F.Paste")
			(net "SMB_CPU0_4_SDA")
		)
		(pad "4" smd rect
			(at -2.175002 1.050036)
			(size 0.6096 1.1684)
			(layers "F.Cu" "F.Mask" "F.Paste")
			(net "GND")
		)
		(pad "5" smd rect
			(at 2.175002 1.050036)
			(size 0.6096 1.1684)
			(layers "F.Cu" "F.Mask" "F.Paste")
			(net "TP_U27_EN")
		)
		(pad "6" smd rect
			(at 2.175002 0.32512)
			(size 0.4318 1.1684)
			(layers "F.Cu" "F.Mask" "F.Paste")
			(net "SMB_CPU0_4_XLTR_SDA")
		)
		(pad "7" smd rect
			(at 2.175002 -0.32512)
			(size 0.4318 1.1684)
			(layers "F.Cu" "F.Mask" "F.Paste")
			(net "SMB_CPU0_4_XLTR_SCL")
		)
		(pad "8" smd rect
			(at 2.175002 -1.050036)
			(size 0.6096 1.1684)
			(layers "F.Cu" "F.Mask" "F.Paste")
			(net "P3V3_AUX")
		)
	)
	(footprint ""
		(layer "F.Cu")
		(at 281.818588 -394.444982 -90)
		(property "Reference" "R2628"
			(at 0 0 270)
			(layer "F.SilkS")
			(hide yes)
			(effects
				(font
					(size 1.27 1.27)
				)
			)
		)
		(property "Value" ""
			(at 0 0 270)
			(layer "F.Fab")
			(effects
				(font
					(size 1.27 1.27)
				)
			)
		)
		(duplicate_pad_numbers_are_jumpers no)
		(fp_line
			(start -0.7874 0.4064)
			(end -0.7874 -0.4064)
			(stroke
				(width 0.1524)
				(type default)
			)
			(layer "F.SilkS")
		)
		(fp_line
			(start 0.7874 0.4064)
			(end -0.7874 0.4064)
			(stroke
				(width 0.1524)
				(type default)
			)
			(layer "F.SilkS")
		)
		(fp_line
			(start -0.7874 -0.4064)
			(end 0.7874 -0.4064)
			(stroke
				(width 0.1524)
				(type default)
			)
			(layer "F.SilkS")
		)
		(fp_line
			(start 0.7874 -0.4064)
			(end 0.7874 0.4064)
			(stroke
				(width 0.1524)
				(type default)
			)
			(layer "F.SilkS")
		)
		(fp_line
			(start -0.67945 0.3048)
			(end -0.67945 -0.305054)
			(stroke
				(width 0.1)
				(type default)
			)
			(layer "F.Fab")
		)
		(fp_line
			(start -0.12065 0.3048)
			(end -0.67945 0.3048)
			(stroke
				(width 0.1)
				(type default)
			)
			(layer "F.Fab")
		)
		(fp_line
			(start 0.120396 0.3048)
			(end 0.120396 0.2794)
			(stroke
				(width 0.1)
				(type default)
			)
			(layer "F.Fab")
		)
		(fp_line
			(start 0.67945 0.3048)
			(end 0.120396 0.3048)
			(stroke
				(width 0.1)
				(type default)
			)
			(layer "F.Fab")
		)
		(fp_line
			(start -0.12065 0.2794)
			(end -0.12065 0.3048)
			(stroke
				(width 0.1)
				(type default)
			)
			(layer "F.Fab")
		)
		(fp_line
			(start 0.120396 0.2794)
			(end -0.12065 0.2794)
			(stroke
				(width 0.1)
				(type default)
			)
			(layer "F.Fab")
		)
		(fp_line
			(start -0.12065 -0.2794)
			(end 0.12065 -0.2794)
			(stroke
				(width 0.1)
				(type default)
			)
			(layer "F.Fab")
		)
		(fp_line
			(start 0.12065 -0.2794)
			(end 0.12065 -0.3048)
			(stroke
				(width 0.1)
				(type default)
			)
			(layer "F.Fab")
		)
		(fp_line
			(start 0.12065 -0.3048)
			(end 0.67945 -0.3048)
			(stroke
				(width 0.1)
				(type default)
			)
			(layer "F.Fab")
		)
		(fp_line
			(start 0.67945 -0.3048)
			(end 0.67945 0.3048)
			(stroke
				(width 0.1)
				(type default)
			)
			(layer "F.Fab")
		)
		(fp_line
			(start -0.67945 -0.305054)
			(end -0.12065 -0.305054)
			(stroke
				(width 0.1)
				(type default)
			)
			(layer "F.Fab")
		)
		(fp_line
			(start -0.12065 -0.305054)
			(end -0.12065 -0.2794)
			(stroke
				(width 0.1)
				(type default)
			)
			(layer "F.Fab")
		)
		(pad "1" smd circle
			(at -0.40005 0 270)
			(size 0 0)
			(layers "F.Cu" "F.Mask" "F.Paste")
			(net "P12V_HSC_TEMP_ALERT_N")
		)
		(pad "2" smd circle
			(at 0.40005 0 270)
			(size 0 0)
			(layers "F.Cu" "F.Mask" "F.Paste")
			(net "P12V_HSC_TEMP_ALERT_R_N")
		)
	)
)
